(kicad_pcb
	(version 20260206)
	(generator "pcbnew")
	(generator_version "10.0")
	(general
		(thickness 1.6)
		(legacy_teardrops no)
	)
	(paper "A4")
	(title_block
		(title "04192023_DAF0TMB3IC0_F0TG_MB_C_brd_V02_OCP.brd")
		(comment 1 "Grand Teton / footprints 1026-1030 of 8354")
	)
	(layers
		(0 "F.Cu" signal "TOP")
		(4 "In1.Cu" signal "GND")
		(6 "In2.Cu" signal "IN1")
		(8 "In3.Cu" signal "GND1")
		(10 "In4.Cu" signal "IN2")
		(12 "In5.Cu" signal "GND2")
		(14 "In6.Cu" signal "IN3")
		(16 "In7.Cu" signal "GND3")
		(18 "In8.Cu" signal "VCC")
		(20 "In9.Cu" signal "VCC1")
		(22 "In10.Cu" signal "GND4")
		(24 "In11.Cu" signal "IN4")
		(26 "In12.Cu" signal "GND5")
		(28 "In13.Cu" signal "IN5")
		(30 "In14.Cu" signal "GND6")
		(32 "In15.Cu" signal "IN6")
		(34 "In16.Cu" signal "GND7")
		(2 "B.Cu" signal "BOTTOM")
		(9 "F.Adhes" user "F.Adhesive")
		(11 "B.Adhes" user "B.Adhesive")
		(13 "F.Paste" user "Package Geometry/Pastemask Top")
		(15 "B.Paste" user "Package Geometry/Pastemask Bottom")
		(5 "F.SilkS" user "Ref Des/Silkscreen Top")
		(7 "B.SilkS" user "Ref Des/Silkscreen Bottom")
		(1 "F.Mask" user "Board Geometry/Soldermask Top")
		(3 "B.Mask" user "Board Geometry/Soldermask Bottom")
		(17 "Dwgs.User" user "User.Drawings")
		(19 "Cmts.User" user "User.Comments")
		(21 "Eco1.User" user "User.Eco1")
		(23 "Eco2.User" user "User.Eco2")
		(25 "Edge.Cuts" user "Board Geometry/Outline")
		(27 "Margin" user)
		(31 "F.CrtYd" user "Package Geometry/Place Bound Top")
		(29 "B.CrtYd" user "Package Geometry/Place Bound Bottom")
		(35 "F.Fab" user "Ref Des/Assembly Top")
		(33 "B.Fab" user "Ref Des/Assembly Bottom")
	)
	(footprint ""
		(layer "F.Cu")
		(at 363.645958 -259.845048)
		(property "Reference" "C3893"
			(at 0 0 0)
			(layer "F.SilkS")
			(hide yes)
			(effects
				(font
					(size 1.27 1.27)
				)
			)
		)
		(property "Value" ""
			(at 0 0 0)
			(layer "F.Fab")
			(effects
				(font
					(size 1.27 1.27)
				)
			)
		)
		(duplicate_pad_numbers_are_jumpers no)
		(fp_line
			(start -0.7874 -0.4064)
			(end 0.7874 -0.4064)
			(stroke
				(width 0.1524)
				(type default)
			)
			(layer "F.SilkS")
		)
		(fp_line
			(start -0.7874 0.4064)
			(end -0.7874 -0.4064)
			(stroke
				(width 0.1524)
				(type default)
			)
			(layer "F.SilkS")
		)
		(fp_line
			(start 0.7874 -0.4064)
			(end 0.7874 0.4064)
			(stroke
				(width 0.1524)
				(type default)
			)
			(layer "F.SilkS")
		)
		(fp_line
			(start 0.7874 0.4064)
			(end -0.7874 0.4064)
			(stroke
				(width 0.1524)
				(type default)
			)
			(layer "F.SilkS")
		)
		(fp_line
			(start -0.67945 -0.305054)
			(end -0.12065 -0.305054)
			(stroke
				(width 0.1)
				(type default)
			)
			(layer "F.Fab")
		)
		(fp_line
			(start -0.67945 0.3048)
			(end -0.67945 -0.305054)
			(stroke
				(width 0.1)
				(type default)
			)
			(layer "F.Fab")
		)
		(fp_line
			(start -0.12065 -0.305054)
			(end -0.12065 -0.2794)
			(stroke
				(width 0.1)
				(type default)
			)
			(layer "F.Fab")
		)
		(fp_line
			(start -0.12065 -0.2794)
			(end 0.12065 -0.2794)
			(stroke
				(width 0.1)
				(type default)
			)
			(layer "F.Fab")
		)
		(fp_line
			(start -0.12065 0.2794)
			(end -0.12065 0.3048)
			(stroke
				(width 0.1)
				(type default)
			)
			(layer "F.Fab")
		)
		(fp_line
			(start -0.12065 0.3048)
			(end -0.67945 0.3048)
			(stroke
				(width 0.1)
				(type default)
			)
			(layer "F.Fab")
		)
		(fp_line
			(start 0.120396 0.2794)
			(end -0.12065 0.2794)
			(stroke
				(width 0.1)
				(type default)
			)
			(layer "F.Fab")
		)
		(fp_line
			(start 0.120396 0.3048)
			(end 0.120396 0.2794)
			(stroke
				(width 0.1)
				(type default)
			)
			(layer "F.Fab")
		)
		(fp_line
			(start 0.12065 -0.3048)
			(end 0.67945 -0.3048)
			(stroke
				(width 0.1)
				(type default)
			)
			(layer "F.Fab")
		)
		(fp_line
			(start 0.12065 -0.2794)
			(end 0.12065 -0.3048)
			(stroke
				(width 0.1)
				(type default)
			)
			(layer "F.Fab")
		)
		(fp_line
			(start 0.67945 -0.3048)
			(end 0.67945 0.3048)
			(stroke
				(width 0.1)
				(type default)
			)
			(layer "F.Fab")
		)
		(fp_line
			(start 0.67945 0.3048)
			(end 0.120396 0.3048)
			(stroke
				(width 0.1)
				(type default)
			)
			(layer "F.Fab")
		)
		(pad "1" smd circle
			(at -0.40005 0)
			(size 0 0)
			(layers "F.Cu" "F.Mask" "F.Paste")
			(net "PVDD11_S3_P0")
		)
		(pad "2" smd circle
			(at 0.40005 0)
			(size 0 0)
			(layers "F.Cu" "F.Mask" "F.Paste")
			(net "GND")
		)
	)
	(footprint ""
		(layer "F.Cu")
		(at 435.208172 -32.173418 -90)
		(property "Reference" "R3869"
			(at 0 0 270)
			(layer "F.SilkS")
			(hide yes)
			(effects
				(font
					(size 1.27 1.27)
				)
			)
		)
		(property "Value" ""
			(at 0 0 270)
			(layer "F.Fab")
			(effects
				(font
					(size 1.27 1.27)
				)
			)
		)
		(duplicate_pad_numbers_are_jumpers no)
		(fp_line
			(start -0.7874 0.4064)
			(end -0.7874 -0.4064)
			(stroke
				(width 0.1524)
				(type default)
			)
			(layer "F.SilkS")
		)
		(fp_line
			(start 0.7874 0.4064)
			(end -0.7874 0.4064)
			(stroke
				(width 0.1524)
				(type default)
			)
			(layer "F.SilkS")
		)
		(fp_line
			(start -0.7874 -0.4064)
			(end 0.7874 -0.4064)
			(stroke
				(width 0.1524)
				(type default)
			)
			(layer "F.SilkS")
		)
		(fp_line
			(start 0.7874 -0.4064)
			(end 0.7874 0.4064)
			(stroke
				(width 0.1524)
				(type default)
			)
			(layer "F.SilkS")
		)
		(fp_line
			(start -0.67945 0.3048)
			(end -0.67945 -0.305054)
			(stroke
				(width 0.1)
				(type default)
			)
			(layer "F.Fab")
		)
		(fp_line
			(start -0.12065 0.3048)
			(end -0.67945 0.3048)
			(stroke
				(width 0.1)
				(type default)
			)
			(layer "F.Fab")
		)
		(fp_line
			(start 0.120396 0.3048)
			(end 0.120396 0.2794)
			(stroke
				(width 0.1)
				(type default)
			)
			(layer "F.Fab")
		)
		(fp_line
			(start 0.67945 0.3048)
			(end 0.120396 0.3048)
			(stroke
				(width 0.1)
				(type default)
			)
			(layer "F.Fab")
		)
		(fp_line
			(start -0.12065 0.2794)
			(end -0.12065 0.3048)
			(stroke
				(width 0.1)
				(type default)
			)
			(layer "F.Fab")
		)
		(fp_line
			(start 0.120396 0.2794)
			(end -0.12065 0.2794)
			(stroke
				(width 0.1)
				(type default)
			)
			(layer "F.Fab")
		)
		(fp_line
			(start -0.12065 -0.2794)
			(end 0.12065 -0.2794)
			(stroke
				(width 0.1)
				(type default)
			)
			(layer "F.Fab")
		)
		(fp_line
			(start 0.12065 -0.2794)
			(end 0.12065 -0.3048)
			(stroke
				(width 0.1)
				(type default)
			)
			(layer "F.Fab")
		)
		(fp_line
			(start 0.12065 -0.3048)
			(end 0.67945 -0.3048)
			(stroke
				(width 0.1)
				(type default)
			)
			(layer "F.Fab")
		)
		(fp_line
			(start 0.67945 -0.3048)
			(end 0.67945 0.3048)
			(stroke
				(width 0.1)
				(type default)
			)
			(layer "F.Fab")
		)
		(fp_line
			(start -0.67945 -0.305054)
			(end -0.12065 -0.305054)
			(stroke
				(width 0.1)
				(type default)
			)
			(layer "F.Fab")
		)
		(fp_line
			(start -0.12065 -0.305054)
			(end -0.12065 -0.2794)
			(stroke
				(width 0.1)
				(type default)
			)
			(layer "F.Fab")
		)
		(pad "1" smd circle
			(at -0.40005 0 270)
			(size 0 0)
			(layers "F.Cu" "F.Mask" "F.Paste")
			(net "P12V_OCP_SENSE_1")
		)
		(pad "2" smd circle
			(at 0.40005 0 270)
			(size 0 0)
			(layers "F.Cu" "F.Mask" "F.Paste")
			(net "P12V_OCP_SFF_ISENSE_MAM_MAM")
		)
	)
	(footprint ""
		(layer "F.Cu")
		(at 372.67515 -182.743856 180)
		(property "Reference" "PU43"
			(at -0.013208 -7.145274 0)
			(unlocked yes)
			(layer "F.SilkS")
			(effects
				(font
					(size 0.7874 0.5842)
					(thickness 0.1524)
				)
				(justify left)
			)
		)
		(property "Value" ""
			(at 0 0 180)
			(layer "F.Fab")
			(effects
				(font
					(size 1.27 1.27)
				)
			)
		)
		(duplicate_pad_numbers_are_jumpers no)
		(fp_line
			(start 2.500122 2.999994)
			(end 2.2987 2.999994)
			(stroke
				(width 0.1524)
				(type default)
			)
			(layer "F.SilkS")
		)
		(fp_line
			(start 2.500122 2.339594)
			(end 2.500122 2.999994)
			(stroke
				(width 0.1524)
				(type default)
			)
			(layer "F.SilkS")
		)
		(fp_line
			(start 2.500122 -2.999994)
			(end 2.500122 -2.44348)
			(stroke
				(width 0.1524)
				(type default)
			)
			(layer "F.SilkS")
		)
		(fp_line
			(start 2.31394 -2.999994)
			(end 2.500122 -2.999994)
			(stroke
				(width 0.1524)
				(type default)
			)
			(layer "F.SilkS")
		)
		(fp_line
			(start -2.2987 2.999994)
			(end -2.500122 2.999994)
			(stroke
				(width 0.1524)
				(type default)
			)
			(layer "F.SilkS")
		)
		(fp_line
			(start -2.500122 2.999994)
			(end -2.500122 2.339594)
			(stroke
				(width 0.1524)
				(type default)
			)
			(layer "F.SilkS")
		)
		(fp_line
			(start -2.500122 0.6604)
			(end -2.500122 0.229108)
			(stroke
				(width 0.1524)
				(type default)
			)
			(layer "F.SilkS")
		)
		(fp_line
			(start -2.500122 -2.529078)
			(end -2.500122 -2.999994)
			(stroke
				(width 0.1524)
				(type default)
			)
			(layer "F.SilkS")
		)
		(fp_line
			(start -2.500122 -2.999994)
			(end -2.24409 -2.999994)
			(stroke
				(width 0.1524)
				(type default)
			)
			(layer "F.SilkS")
		)
		(fp_poly
			(pts
				(xy -2.755138 -2.475484) (xy -3.387598 -2.686304) (xy -2.965958 -3.108198)
			)
			(stroke
				(width 0)
				(type default)
			)
			(fill yes)
			(layer "F.SilkS")
		)
		(fp_line
			(start 2.500122 2.999994)
			(end -2.500122 2.999994)
			(stroke
				(width 0.1)
				(type default)
			)
			(layer "F.Fab")
		)
		(fp_line
			(start 2.500122 -2.999994)
			(end 2.500122 2.999994)
			(stroke
				(width 0.1)
				(type default)
			)
			(layer "F.Fab")
		)
		(fp_line
			(start -2.500122 2.999994)
			(end -2.500122 -2.999994)
			(stroke
				(width 0.1)
				(type default)
			)
			(layer "F.Fab")
		)
		(fp_line
			(start -2.500122 -2.999994)
			(end 2.500122 -2.999994)
			(stroke
				(width 0.1)
				(type default)
			)
			(layer "F.Fab")
		)
		(fp_poly
			(pts
				(xy -4.218432 -2.783078) (xy -4.218432 -1.767078) (xy -3.202432 -2.275078)
			)
			(stroke
				(width 0)
				(type default)
			)
			(fill yes)
			(layer "F.Fab")
		)
		(pad "1" smd rect
			(at -2.400046 -2.275078 270)
			(size 0.2286 0.6096)
			(layers "F.Cu" "F.Mask" "F.Paste")
			(net "PVDDCR_CPU0_P0_VOS2")
		)
		(pad "2" smd rect
			(at -2.400046 -1.82499 270)
			(size 0.2286 0.6096)
			(layers "F.Cu" "F.Mask" "F.Paste")
			(net "GND")
		)
		(pad "3" smd rect
			(at -2.400046 -1.374902 270)
			(size 0.2286 0.6096)
			(layers "F.Cu" "F.Mask" "F.Paste")
			(net "PVDDCR_CPU0_P0_VCC2")
		)
		(pad "4" smd rect
			(at -2.400046 -0.925068 270)
			(size 0.2286 0.6096)
			(layers "F.Cu" "F.Mask" "F.Paste")
			(net "PVDDCR_CPU0_P0_PVCC")
		)
		(pad "5" smd rect
			(at -2.400046 -0.47498 270)
			(size 0.2286 0.6096)
			(layers "F.Cu" "F.Mask" "F.Paste")
			(net "GND")
		)
		(pad "6" smd rect
			(at -2.400046 -0.024892 270)
			(size 0.2286 0.6096)
			(layers "F.Cu" "F.Mask" "F.Paste")
			(net "NC_PVDDCR_CPU0_P0_GL1_2")
		)
		(pad "7_9-20_24" smd circle
			(at 0 1.150112 270)
			(size 0 0)
			(layers "F.Cu" "F.Mask" "F.Paste")
			(net "GND")
		)
		(pad "10_19" smd rect
			(at 0 2.899918 270)
			(size 0.6096 4.318)
			(layers "F.Cu" "F.Mask" "F.Paste")
			(net "SW_PVDDCR_CPU0_P0_SW2")
		)
		(pad "25_29" smd rect
			(at 1.549908 -1.279906 90)
			(size 2.0574 2.3114)
			(layers "F.Cu" "F.Mask" "F.Paste")
			(net "SW_P12V_AUX_PVDDCR_CPU0_P0_FLT")
		)
		(pad "30" smd rect
			(at 2.05994 -2.899918 180)
			(size 0.2286 0.6096)
			(layers "F.Cu" "F.Mask" "F.Paste")
			(net "SW_P12V_AUX_PVDDCR_CPU0_P0_FLT")
		)
		(pad "31" smd rect
			(at 1.610106 -2.899918 180)
			(size 0.2286 0.6096)
			(layers "F.Cu" "F.Mask" "F.Paste")
			(net "NC_PVDDCR_CPU0_P0_DNC2")
		)
		(pad "32" smd rect
			(at 1.160018 -2.899918 180)
			(size 0.2286 0.6096)
			(layers "F.Cu" "F.Mask" "F.Paste")
			(net "SW_PVDDCR_CPU0_P0_PH2")
		)
		(pad "33" smd rect
			(at 0.70993 -2.899918 180)
			(size 0.2286 0.6096)
			(layers "F.Cu" "F.Mask" "F.Paste")
			(net "SW_PVDDCR_CPU0_P0_BOOT2")
		)
		(pad "34" smd rect
			(at 0.260096 -2.899918 180)
			(size 0.2286 0.6096)
			(layers "F.Cu" "F.Mask" "F.Paste")
			(net "PVDDCR_CPU0_P0_PWM2")
		)
		(pad "35" smd rect
			(at -0.189992 -2.899918 180)
			(size 0.2286 0.6096)
			(layers "F.Cu" "F.Mask" "F.Paste")
			(net "PVDDCR_CPU0_P0_VCC2")
		)
		(pad "36" smd rect
			(at -0.64008 -2.899918 180)
			(size 0.2286 0.6096)
			(layers "F.Cu" "F.Mask" "F.Paste")
			(net "PVDDCR_CPU0_P0_TEMP0")
		)
		(pad "37" smd rect
			(at -1.089914 -2.899918 180)
			(size 0.2286 0.6096)
			(layers "F.Cu" "F.Mask" "F.Paste")
			(net "PVDDCR_CPU0_P0_LSET2")
		)
		(pad "38" smd rect
			(at -1.540002 -2.899918 180)
			(size 0.2286 0.6096)
			(layers "F.Cu" "F.Mask" "F.Paste")
			(net "PVDDCR_CPU0_P0_IMON2")
		)
		(pad "39" smd rect
			(at -1.99009 -2.899918 180)
			(size 0.2286 0.6096)
			(layers "F.Cu" "F.Mask" "F.Paste")
			(net "PVDDCR_CPU0_P0_VCCS")
		)
		(pad "40" smd rect
			(at -0.87503 -1.27508 180)
			(size 1.7526 1.9558)
			(layers "F.Cu" "F.Mask" "F.Paste")
			(net "GND")
		)
		(pad "41" smd rect
			(at -1.525016 0.249936 90)
			(size 0.3048 0.4572)
			(layers "F.Cu" "F.Mask" "F.Paste")
			(net "NC_PVDDCR_CPU0_P0_GL2_2")
		)
		(zone
			(layer "F.Cu")
			(hatch none 0.5)
			(connect_pads
				(clearance 0)
			)
			(min_thickness 0.25)
			(keepout
				(tracks not_allowed)
				(vias allowed)
				(pads allowed)
				(copperpour not_allowed)
				(footprints allowed)
			)
			(placement
				(enabled no)
				(sheetname "")
			)
			(fill
				(thermal_gap 0.5)
				(thermal_bridge_width 0.5)
				(island_removal_mode 0)
			)
			(polygon
				(pts
					(xy 375.175272 -185.32729) (xy 375.175272 -184.99455) (xy 370.175028 -184.99455) (xy 370.175028 -185.318654)
					(xy 370.46535 -185.318654) (xy 370.46535 -185.288174) (xy 374.88495 -185.288174) (xy 374.88495 -185.32729)
				)
			)
		)
		(zone
			(layer "F.Cu")
			(hatch none 0.5)
			(connect_pads
				(clearance 0)
			)
			(min_thickness 0.25)
			(keepout
				(tracks not_allowed)
				(vias allowed)
				(pads allowed)
				(copperpour not_allowed)
				(footprints allowed)
			)
			(placement
				(enabled no)
				(sheetname "")
			)
			(fill
				(thermal_gap 0.5)
				(thermal_bridge_width 0.5)
				(island_removal_mode 0)
			)
			(polygon
				(pts
					(xy 372.62308 -182.497476) (xy 372.62308 -180.440076) (xy 374.47728 -180.440076) (xy 374.47728 -180.681122)
					(xy 374.719596 -180.681122) (xy 374.719596 -180.199538) (xy 370.902484 -180.199538) (xy 370.902484 -180.38445)
					(xy 372.331742 -180.38445) (xy 372.331742 -182.54345) (xy 370.175028 -182.54345) (xy 370.175028 -182.793132)
					(xy 372.327424 -182.793132)
				)
			)
		)
	)
	(footprint ""
		(layer "F.Cu")
		(at 392.840972 -388.767828)
		(property "Reference" "C870"
			(at 0 0 0)
			(layer "F.SilkS")
			(hide yes)
			(effects
				(font
					(size 1.27 1.27)
				)
			)
		)
		(property "Value" ""
			(at 0 0 0)
			(layer "F.Fab")
			(effects
				(font
					(size 1.27 1.27)
				)
			)
		)
		(duplicate_pad_numbers_are_jumpers no)
		(fp_line
			(start -0.299974 -0.150114)
			(end 0.299974 -0.150114)
			(stroke
				(width 0.1)
				(type default)
			)
			(layer "F.Fab")
		)
		(fp_line
			(start -0.299974 0.150114)
			(end -0.299974 -0.150114)
			(stroke
				(width 0.1)
				(type default)
			)
			(layer "F.Fab")
		)
		(fp_line
			(start 0.299974 -0.150114)
			(end 0.299974 0.150114)
			(stroke
				(width 0.1)
				(type default)
			)
			(layer "F.Fab")
		)
		(fp_line
			(start 0.299974 0.150114)
			(end -0.299974 0.150114)
			(stroke
				(width 0.1)
				(type default)
			)
			(layer "F.Fab")
		)
		(pad "1" smd rect
			(at -0.2667 0)
			(size 0.3048 0.381)
			(layers "F.Cu" "F.Mask" "F.Paste")
			(net "P5E_CPU0_P3_TX_C_DN<15>")
		)
		(pad "2" smd rect
			(at 0.2667 0)
			(size 0.3048 0.381)
			(layers "F.Cu" "F.Mask" "F.Paste")
			(net "P5E_CPU0_P3_TX_DN<15>")
		)
	)
	(footprint ""
		(layer "F.Cu")
		(at 345.467686 -23.8887 -90)
		(property "Reference" "R947"
			(at 0 0 270)
			(layer "F.SilkS")
			(hide yes)
			(effects
				(font
					(size 1.27 1.27)
				)
			)
		)
		(property "Value" ""
			(at 0 0 270)
			(layer "F.Fab")
			(effects
				(font
					(size 1.27 1.27)
				)
			)
		)
		(duplicate_pad_numbers_are_jumpers no)
		(fp_line
			(start -0.7874 0.4064)
			(end -0.7874 -0.4064)
			(stroke
				(width 0.1524)
				(type default)
			)
			(layer "F.SilkS")
		)
		(fp_line
			(start 0.7874 0.4064)
			(end -0.7874 0.4064)
			(stroke
				(width 0.1524)
				(type default)
			)
			(layer "F.SilkS")
		)
		(fp_line
			(start -0.7874 -0.4064)
			(end 0.7874 -0.4064)
			(stroke
				(width 0.1524)
				(type default)
			)
			(layer "F.SilkS")
		)
		(fp_line
			(start 0.7874 -0.4064)
			(end 0.7874 0.4064)
			(stroke
				(width 0.1524)
				(type default)
			)
			(layer "F.SilkS")
		)
		(fp_line
			(start -0.67945 0.3048)
			(end -0.67945 -0.305054)
			(stroke
				(width 0.1)
				(type default)
			)
			(layer "F.Fab")
		)
		(fp_line
			(start -0.12065 0.3048)
			(end -0.67945 0.3048)
			(stroke
				(width 0.1)
				(type default)
			)
			(layer "F.Fab")
		)
		(fp_line
			(start 0.120396 0.3048)
			(end 0.120396 0.2794)
			(stroke
				(width 0.1)
				(type default)
			)
			(layer "F.Fab")
		)
		(fp_line
			(start 0.67945 0.3048)
			(end 0.120396 0.3048)
			(stroke
				(width 0.1)
				(type default)
			)
			(layer "F.Fab")
		)
		(fp_line
			(start -0.12065 0.2794)
			(end -0.12065 0.3048)
			(stroke
				(width 0.1)
				(type default)
			)
			(layer "F.Fab")
		)
		(fp_line
			(start 0.120396 0.2794)
			(end -0.12065 0.2794)
			(stroke
				(width 0.1)
				(type default)
			)
			(layer "F.Fab")
		)
		(fp_line
			(start -0.12065 -0.2794)
			(end 0.12065 -0.2794)
			(stroke
				(width 0.1)
				(type default)
			)
			(layer "F.Fab")
		)
		(fp_line
			(start 0.12065 -0.2794)
			(end 0.12065 -0.3048)
			(stroke
				(width 0.1)
				(type default)
			)
			(layer "F.Fab")
		)
		(fp_line
			(start 0.12065 -0.3048)
			(end 0.67945 -0.3048)
			(stroke
				(width 0.1)
				(type default)
			)
			(layer "F.Fab")
		)
		(fp_line
			(start 0.67945 -0.3048)
			(end 0.67945 0.3048)
			(stroke
				(width 0.1)
				(type default)
			)
			(layer "F.Fab")
		)
		(fp_line
			(start -0.67945 -0.305054)
			(end -0.12065 -0.305054)
			(stroke
				(width 0.1)
				(type default)
			)
			(layer "F.Fab")
		)
		(fp_line
			(start -0.12065 -0.305054)
			(end -0.12065 -0.2794)
			(stroke
				(width 0.1)
				(type default)
			)
			(layer "F.Fab")
		)
		(pad "1" smd circle
			(at -0.40005 0 270)
			(size 0 0)
			(layers "F.Cu" "F.Mask" "F.Paste")
			(net "P3V3_AUX")
		)
		(pad "2" smd circle
			(at 0.40005 0 270)
			(size 0 0)
			(layers "F.Cu" "F.Mask" "F.Paste")
			(net "SMERR_LED")
		)
	)
)
